# T6G (Grand Teton) — schematic netlist excerpt (pin names and nets, part order shuffled) for the footprints in the layout excerpt that follows; sources: Cadence DE-HDL packaged netlist, KiCad conversion of 04192023_DAF0TMB3IC0_F0TG_MB_C_brd_V02_OCP.brd

PR34  Q_RES  0 5% CHIP  pkg 0402LF  page 207 : A = NC_PVDD11_S3_P0_IMON5 ; B = GND
R1906  Q_RES  1K 1% CHIP  pkg 0402LF  page 134 : A = P3V3_AUX ; B = OCP_SFF_PRSNT2_R_N

(kicad_pcb
	(version 20260206)
	(generator "pcbnew")
	(generator_version "10.0")
	(general
		(thickness 1.6)
		(legacy_teardrops no)
	)
	(paper "A4")
	(title_block
		(title "04192023_DAF0TMB3IC0_F0TG_MB_C_brd_V02_OCP.brd")
		(comment 1 "Grand Teton / footprints 3164-3165 of 8354")
	)
	(layers
		(0 "F.Cu" signal "TOP")
		(4 "In1.Cu" signal "GND")
		(6 "In2.Cu" signal "IN1")
		(8 "In3.Cu" signal "GND1")
		(10 "In4.Cu" signal "IN2")
		(12 "In5.Cu" signal "GND2")
		(14 "In6.Cu" signal "IN3")
		(16 "In7.Cu" signal "GND3")
		(18 "In8.Cu" signal "VCC")
		(20 "In9.Cu" signal "VCC1")
		(22 "In10.Cu" signal "GND4")
		(24 "In11.Cu" signal "IN4")
		(26 "In12.Cu" signal "GND5")
		(28 "In13.Cu" signal "IN5")
		(30 "In14.Cu" signal "GND6")
		(32 "In15.Cu" signal "IN6")
		(34 "In16.Cu" signal "GND7")
		(2 "B.Cu" signal "BOTTOM")
		(9 "F.Adhes" user "F.Adhesive")
		(11 "B.Adhes" user "B.Adhesive")
		(13 "F.Paste" user "Package Geometry/Pastemask Top")
		(15 "B.Paste" user "Package Geometry/Pastemask Bottom")
		(5 "F.SilkS" user "Ref Des/Silkscreen Top")
		(7 "B.SilkS" user "Ref Des/Silkscreen Bottom")
		(1 "F.Mask" user "Board Geometry/Soldermask Top")
		(3 "B.Mask" user "Board Geometry/Soldermask Bottom")
		(17 "Dwgs.User" user "User.Drawings")
		(19 "Cmts.User" user "User.Comments")
		(21 "Eco1.User" user "User.Eco1")
		(23 "Eco2.User" user "User.Eco2")
		(25 "Edge.Cuts" user "Board Geometry/Outline")
		(27 "Margin" user)
		(31 "F.CrtYd" user "Package Geometry/Place Bound Top")
		(29 "B.CrtYd" user "Package Geometry/Place Bound Bottom")
		(35 "F.Fab" user "Ref Des/Assembly Top")
		(33 "B.Fab" user "Ref Des/Assembly Bottom")
	)
	(footprint ""
		(layer "F.Cu")
		(at 453.719946 -104.249728)
		(property "Reference" "R1906"
			(at 0 0 0)
			(layer "F.SilkS")
			(hide yes)
			(effects
				(font
					(size 1.27 1.27)
				)
			)
		)
		(property "Value" ""
			(at 0 0 0)
			(layer "F.Fab")
			(effects
				(font
					(size 1.27 1.27)
				)
			)
		)
		(duplicate_pad_numbers_are_jumpers no)
		(fp_line
			(start -0.7874 -0.4064)
			(end 0.7874 -0.4064)
			(stroke
				(width 0.1524)
				(type default)
			)
			(layer "F.SilkS")
		)
		(fp_line
			(start -0.7874 0.4064)
			(end -0.7874 -0.4064)
			(stroke
				(width 0.1524)
				(type default)
			)
			(layer "F.SilkS")
		)
		(fp_line
			(start 0.7874 -0.4064)
			(end 0.7874 0.4064)
			(stroke
				(width 0.1524)
				(type default)
			)
			(layer "F.SilkS")
		)
		(fp_line
			(start 0.7874 0.4064)
			(end -0.7874 0.4064)
			(stroke
				(width 0.1524)
				(type default)
			)
			(layer "F.SilkS")
		)
		(fp_line
			(start -0.67945 -0.305054)
			(end -0.12065 -0.305054)
			(stroke
				(width 0.1)
				(type default)
			)
			(layer "F.Fab")
		)
		(fp_line
			(start -0.67945 0.3048)
			(end -0.67945 -0.305054)
			(stroke
				(width 0.1)
				(type default)
			)
			(layer "F.Fab")
		)
		(fp_line
			(start -0.12065 -0.305054)
			(end -0.12065 -0.2794)
			(stroke
				(width 0.1)
				(type default)
			)
			(layer "F.Fab")
		)
		(fp_line
			(start -0.12065 -0.2794)
			(end 0.12065 -0.2794)
			(stroke
				(width 0.1)
				(type default)
			)
			(layer "F.Fab")
		)
		(fp_line
			(start -0.12065 0.2794)
			(end -0.12065 0.3048)
			(stroke
				(width 0.1)
				(type default)
			)
			(layer "F.Fab")
		)
		(fp_line
			(start -0.12065 0.3048)
			(end -0.67945 0.3048)
			(stroke
				(width 0.1)
				(type default)
			)
			(layer "F.Fab")
		)
		(fp_line
			(start 0.120396 0.2794)
			(end -0.12065 0.2794)
			(stroke
				(width 0.1)
				(type default)
			)
			(layer "F.Fab")
		)
		(fp_line
			(start 0.120396 0.3048)
			(end 0.120396 0.2794)
			(stroke
				(width 0.1)
				(type default)
			)
			(layer "F.Fab")
		)
		(fp_line
			(start 0.12065 -0.3048)
			(end 0.67945 -0.3048)
			(stroke
				(width 0.1)
				(type default)
			)
			(layer "F.Fab")
		)
		(fp_line
			(start 0.12065 -0.2794)
			(end 0.12065 -0.3048)
			(stroke
				(width 0.1)
				(type default)
			)
			(layer "F.Fab")
		)
		(fp_line
			(start 0.67945 -0.3048)
			(end 0.67945 0.3048)
			(stroke
				(width 0.1)
				(type default)
			)
			(layer "F.Fab")
		)
		(fp_line
			(start 0.67945 0.3048)
			(end 0.120396 0.3048)
			(stroke
				(width 0.1)
				(type default)
			)
			(layer "F.Fab")
		)
		(pad "1" smd circle
			(at -0.40005 0)
			(size 0 0)
			(layers "F.Cu" "F.Mask" "F.Paste")
			(net "P3V3_AUX")
		)
		(pad "2" smd circle
			(at 0.40005 0)
			(size 0 0)
			(layers "F.Cu" "F.Mask" "F.Paste")
			(net "OCP_SFF_PRSNT2_R_N")
		)
	)
	(footprint ""
		(layer "F.Cu")
		(at 420.833296 -357.688134 -90)
		(property "Reference" "PR34"
			(at 0 0 270)
			(layer "F.SilkS")
			(hide yes)
			(effects
				(font
					(size 1.27 1.27)
				)
			)
		)
		(property "Value" ""
			(at 0 0 270)
			(layer "F.Fab")
			(effects
				(font
					(size 1.27 1.27)
				)
			)
		)
		(duplicate_pad_numbers_are_jumpers no)
		(fp_line
			(start -0.7874 0.4064)
			(end -0.7874 -0.4064)
			(stroke
				(width 0.1524)
				(type default)
			)
			(layer "F.SilkS")
		)
		(fp_line
			(start 0.7874 0.4064)
			(end -0.7874 0.4064)
			(stroke
				(width 0.1524)
				(type default)
			)
			(layer "F.SilkS")
		)
		(fp_line
			(start -0.7874 -0.4064)
			(end 0.7874 -0.4064)
			(stroke
				(width 0.1524)
				(type default)
			)
			(layer "F.SilkS")
		)
		(fp_line
			(start 0.7874 -0.4064)
			(end 0.7874 0.4064)
			(stroke
				(width 0.1524)
				(type default)
			)
			(layer "F.SilkS")
		)
		(fp_line
			(start -0.67945 0.3048)
			(end -0.67945 -0.305054)
			(stroke
				(width 0.1)
				(type default)
			)
			(layer "F.Fab")
		)
		(fp_line
			(start -0.12065 0.3048)
			(end -0.67945 0.3048)
			(stroke
				(width 0.1)
				(type default)
			)
			(layer "F.Fab")
		)
		(fp_line
			(start 0.120396 0.3048)
			(end 0.120396 0.2794)
			(stroke
				(width 0.1)
				(type default)
			)
			(layer "F.Fab")
		)
		(fp_line
			(start 0.67945 0.3048)
			(end 0.120396 0.3048)
			(stroke
				(width 0.1)
				(type default)
			)
			(layer "F.Fab")
		)
		(fp_line
			(start -0.12065 0.2794)
			(end -0.12065 0.3048)
			(stroke
				(width 0.1)
				(type default)
			)
			(layer "F.Fab")
		)
		(fp_line
			(start 0.120396 0.2794)
			(end -0.12065 0.2794)
			(stroke
				(width 0.1)
				(type default)
			)
			(layer "F.Fab")
		)
		(fp_line
			(start -0.12065 -0.2794)
			(end 0.12065 -0.2794)
			(stroke
				(width 0.1)
				(type default)
			)
			(layer "F.Fab")
		)
		(fp_line
			(start 0.12065 -0.2794)
			(end 0.12065 -0.3048)
			(stroke
				(width 0.1)
				(type default)
			)
			(layer "F.Fab")
		)
		(fp_line
			(start 0.12065 -0.3048)
			(end 0.67945 -0.3048)
			(stroke
				(width 0.1)
				(type default)
			)
			(layer "F.Fab")
		)
		(fp_line
			(start 0.67945 -0.3048)
			(end 0.67945 0.3048)
			(stroke
				(width 0.1)
				(type default)
			)
			(layer "F.Fab")
		)
		(fp_line
			(start -0.67945 -0.305054)
			(end -0.12065 -0.305054)
			(stroke
				(width 0.1)
				(type default)
			)
			(layer "F.Fab")
		)
		(fp_line
			(start -0.12065 -0.305054)
			(end -0.12065 -0.2794)
			(stroke
				(width 0.1)
				(type default)
			)
			(layer "F.Fab")
		)
		(pad "1" smd circle
			(at -0.40005 0 270)
			(size 0 0)
			(layers "F.Cu" "F.Mask" "F.Paste")
			(net "NC_PVDD11_S3_P0_IMON5")
		)
		(pad "2" smd circle
			(at 0.40005 0 270)
			(size 0 0)
			(layers "F.Cu" "F.Mask" "F.Paste")
			(net "GND")
		)
	)
)
